# S9S_MB_2U (Grand Teton) — schematic netlist excerpt (pin names and nets, part order shuffled) for the footprints in the layout excerpt that follows; sources: Cadence DE-HDL packaged netlist, KiCad conversion of 03242023_DA0F0TMBIJ0_F0T_Motherboard_J_brd_V01_OCP.brd

R1008  Q_RES  1K 1% EMPTY  pkg 0402LF  page 119 : A = PVNN_TERM_CPU1 ; B = PU_TAP_ODT_CPU1_EN
R278  Q_RES  240 1% EMPTY  pkg 0402LF  page 119 : A = PVNN_TERM_CPU0 ; B = H_CPU0_BMCINIT_LVC1

(kicad_pcb
	(version 20260206)
	(generator "pcbnew")
	(generator_version "10.0")
	(general
		(thickness 1.6)
		(legacy_teardrops no)
	)
	(paper "A4")
	(title_block
		(title "03242023_DA0F0TMBIJ0_F0T_Motherboard_J_brd_V01_OCP.brd")
		(comment 1 "Grand Teton / footprints 4816-4817 of 6105")
	)
	(layers
		(0 "F.Cu" signal "TOP")
		(4 "In1.Cu" signal "GND")
		(6 "In2.Cu" signal "IN1")
		(8 "In3.Cu" signal "GND1")
		(10 "In4.Cu" signal "IN2")
		(12 "In5.Cu" signal "GND2")
		(14 "In6.Cu" signal "IN3")
		(16 "In7.Cu" signal "GND3")
		(18 "In8.Cu" signal "VCC")
		(20 "In9.Cu" signal "VCC1")
		(22 "In10.Cu" signal "GND4")
		(24 "In11.Cu" signal "IN4")
		(26 "In12.Cu" signal "GND5")
		(28 "In13.Cu" signal "IN5")
		(30 "In14.Cu" signal "GND6")
		(32 "In15.Cu" signal "IN6")
		(34 "In16.Cu" signal "GND7")
		(2 "B.Cu" signal "BOTTOM")
		(9 "F.Adhes" user "F.Adhesive")
		(11 "B.Adhes" user "B.Adhesive")
		(13 "F.Paste" user "Package Geometry/Pastemask Top")
		(15 "B.Paste" user "Package Geometry/Pastemask Bottom")
		(5 "F.SilkS" user "Ref Des/Silkscreen Top")
		(7 "B.SilkS" user "Ref Des/Silkscreen Bottom")
		(1 "F.Mask" user "Board Geometry/Soldermask Top")
		(3 "B.Mask" user "Board Geometry/Soldermask Bottom")
		(17 "Dwgs.User" user "User.Drawings")
		(19 "Cmts.User" user "User.Comments")
		(21 "Eco1.User" user "User.Eco1")
		(23 "Eco2.User" user "User.Eco2")
		(25 "Edge.Cuts" user "Board Geometry/Outline")
		(27 "Margin" user)
		(31 "F.CrtYd" user "Package Geometry/Place Bound Top")
		(29 "B.CrtYd" user "Package Geometry/Place Bound Bottom")
		(35 "F.Fab" user "Ref Des/Assembly Top")
		(33 "B.Fab" user "Ref Des/Assembly Bottom")
	)
	(footprint ""
		(layer "B.Cu")
		(at 328.169778 -185.09869 -90)
		(property "Reference" "R278"
			(at 0 0 90)
			(layer "B.SilkS")
			(hide yes)
			(effects
				(font
					(size 1.27 1.27)
				)
				(justify mirror)
			)
		)
		(property "Value" ""
			(at 0 0 90)
			(layer "B.Fab")
			(effects
				(font
					(size 1.27 1.27)
				)
				(justify mirror)
			)
		)
		(duplicate_pad_numbers_are_jumpers no)
		(fp_line
			(start -0.7874 0.4064)
			(end 0.7874 0.4064)
			(stroke
				(width 0.1524)
				(type default)
			)
			(layer "B.SilkS")
		)
		(fp_line
			(start 0.7874 0.4064)
			(end 0.7874 -0.4064)
			(stroke
				(width 0.1524)
				(type default)
			)
			(layer "B.SilkS")
		)
		(fp_line
			(start -0.7874 -0.4064)
			(end -0.7874 0.4064)
			(stroke
				(width 0.1524)
				(type default)
			)
			(layer "B.SilkS")
		)
		(fp_line
			(start 0.7874 -0.4064)
			(end -0.7874 -0.4064)
			(stroke
				(width 0.1524)
				(type default)
			)
			(layer "B.SilkS")
		)
		(fp_line
			(start -0.67945 0.3048)
			(end -0.120396 0.3048)
			(stroke
				(width 0.1)
				(type default)
			)
			(layer "B.Fab")
		)
		(fp_line
			(start -0.120396 0.3048)
			(end -0.120396 0.2794)
			(stroke
				(width 0.1)
				(type default)
			)
			(layer "B.Fab")
		)
		(fp_line
			(start 0.12065 0.3048)
			(end 0.67945 0.3048)
			(stroke
				(width 0.1)
				(type default)
			)
			(layer "B.Fab")
		)
		(fp_line
			(start 0.67945 0.3048)
			(end 0.67945 -0.305054)
			(stroke
				(width 0.1)
				(type default)
			)
			(layer "B.Fab")
		)
		(fp_line
			(start -0.120396 0.2794)
			(end 0.12065 0.2794)
			(stroke
				(width 0.1)
				(type default)
			)
			(layer "B.Fab")
		)
		(fp_line
			(start 0.12065 0.2794)
			(end 0.12065 0.3048)
			(stroke
				(width 0.1)
				(type default)
			)
			(layer "B.Fab")
		)
		(fp_line
			(start -0.12065 -0.2794)
			(end -0.12065 -0.3048)
			(stroke
				(width 0.1)
				(type default)
			)
			(layer "B.Fab")
		)
		(fp_line
			(start 0.12065 -0.2794)
			(end -0.12065 -0.2794)
			(stroke
				(width 0.1)
				(type default)
			)
			(layer "B.Fab")
		)
		(fp_line
			(start -0.67945 -0.3048)
			(end -0.67945 0.3048)
			(stroke
				(width 0.1)
				(type default)
			)
			(layer "B.Fab")
		)
		(fp_line
			(start -0.12065 -0.3048)
			(end -0.67945 -0.3048)
			(stroke
				(width 0.1)
				(type default)
			)
			(layer "B.Fab")
		)
		(fp_line
			(start 0.12065 -0.305054)
			(end 0.12065 -0.2794)
			(stroke
				(width 0.1)
				(type default)
			)
			(layer "B.Fab")
		)
		(fp_line
			(start 0.67945 -0.305054)
			(end 0.12065 -0.305054)
			(stroke
				(width 0.1)
				(type default)
			)
			(layer "B.Fab")
		)
		(pad "1" smd circle
			(at 0.40005 0 90)
			(size 0 0)
			(layers "B.Cu" "B.Mask" "B.Paste")
			(net "PVNN_TERM_CPU0")
		)
		(pad "2" smd circle
			(at -0.40005 0 90)
			(size 0 0)
			(layers "B.Cu" "B.Mask" "B.Paste")
			(net "H_CPU0_BMCINIT_LVC1")
		)
	)
	(footprint ""
		(layer "B.Cu")
		(at 68.337684 -185.791856 -90)
		(property "Reference" "R1008"
			(at 0 0 90)
			(layer "B.SilkS")
			(hide yes)
			(effects
				(font
					(size 1.27 1.27)
				)
				(justify mirror)
			)
		)
		(property "Value" ""
			(at 0 0 90)
			(layer "B.Fab")
			(effects
				(font
					(size 1.27 1.27)
				)
				(justify mirror)
			)
		)
		(duplicate_pad_numbers_are_jumpers no)
		(fp_line
			(start -0.7874 0.4064)
			(end 0.7874 0.4064)
			(stroke
				(width 0.1524)
				(type default)
			)
			(layer "B.SilkS")
		)
		(fp_line
			(start 0.7874 0.4064)
			(end 0.7874 -0.4064)
			(stroke
				(width 0.1524)
				(type default)
			)
			(layer "B.SilkS")
		)
		(fp_line
			(start -0.7874 -0.4064)
			(end -0.7874 0.4064)
			(stroke
				(width 0.1524)
				(type default)
			)
			(layer "B.SilkS")
		)
		(fp_line
			(start 0.7874 -0.4064)
			(end -0.7874 -0.4064)
			(stroke
				(width 0.1524)
				(type default)
			)
			(layer "B.SilkS")
		)
		(fp_line
			(start -0.67945 0.3048)
			(end -0.120396 0.3048)
			(stroke
				(width 0.1)
				(type default)
			)
			(layer "B.Fab")
		)
		(fp_line
			(start -0.120396 0.3048)
			(end -0.120396 0.2794)
			(stroke
				(width 0.1)
				(type default)
			)
			(layer "B.Fab")
		)
		(fp_line
			(start 0.12065 0.3048)
			(end 0.67945 0.3048)
			(stroke
				(width 0.1)
				(type default)
			)
			(layer "B.Fab")
		)
		(fp_line
			(start 0.67945 0.3048)
			(end 0.67945 -0.305054)
			(stroke
				(width 0.1)
				(type default)
			)
			(layer "B.Fab")
		)
		(fp_line
			(start -0.120396 0.2794)
			(end 0.12065 0.2794)
			(stroke
				(width 0.1)
				(type default)
			)
			(layer "B.Fab")
		)
		(fp_line
			(start 0.12065 0.2794)
			(end 0.12065 0.3048)
			(stroke
				(width 0.1)
				(type default)
			)
			(layer "B.Fab")
		)
		(fp_line
			(start -0.12065 -0.2794)
			(end -0.12065 -0.3048)
			(stroke
				(width 0.1)
				(type default)
			)
			(layer "B.Fab")
		)
		(fp_line
			(start 0.12065 -0.2794)
			(end -0.12065 -0.2794)
			(stroke
				(width 0.1)
				(type default)
			)
			(layer "B.Fab")
		)
		(fp_line
			(start -0.67945 -0.3048)
			(end -0.67945 0.3048)
			(stroke
				(width 0.1)
				(type default)
			)
			(layer "B.Fab")
		)
		(fp_line
			(start -0.12065 -0.3048)
			(end -0.67945 -0.3048)
			(stroke
				(width 0.1)
				(type default)
			)
			(layer "B.Fab")
		)
		(fp_line
			(start 0.12065 -0.305054)
			(end 0.12065 -0.2794)
			(stroke
				(width 0.1)
				(type default)
			)
			(layer "B.Fab")
		)
		(fp_line
			(start 0.67945 -0.305054)
			(end 0.12065 -0.305054)
			(stroke
				(width 0.1)
				(type default)
			)
			(layer "B.Fab")
		)
		(pad "1" smd circle
			(at 0.40005 0 90)
			(size 0 0)
			(layers "B.Cu" "B.Mask" "B.Paste")
			(net "PVNN_TERM_CPU1")
		)
		(pad "2" smd circle
			(at -0.40005 0 90)
			(size 0 0)
			(layers "B.Cu" "B.Mask" "B.Paste")
			(net "PU_TAP_ODT_CPU1_EN")
		)
	)
)
